(kicad_pcb
	(version 20221018)
	(generator pcbnew)
	(general
    (thickness 0.908)
  )
	(paper "A4")
	(title_block
    (title "HDMI-MIPI Bridge")
    (date "2024-04-24")
    (rev "1.3.2")
		(comment 9 "footprints 1-2 of 121")
	)
	(layers
    (0 "F.Cu" signal)
    (1 "In1.Cu" signal)
    (2 "In2.Cu" signal)
    (31 "B.Cu" signal)
    (32 "B.Adhes" user "B.Adhesive")
    (33 "F.Adhes" user "F.Adhesive")
    (34 "B.Paste" user)
    (35 "F.Paste" user)
    (36 "B.SilkS" user "B.Silkscreen")
    (37 "F.SilkS" user "F.Silkscreen")
    (38 "B.Mask" user)
    (39 "F.Mask" user)
    (40 "Dwgs.User" user "User.Drawings")
    (41 "Cmts.User" user "User.Comments")
    (42 "Eco1.User" user "User.Eco1")
    (43 "Eco2.User" user "User.Eco2")
    (44 "Edge.Cuts" user)
    (45 "Margin" user)
    (46 "B.CrtYd" user "B.Courtyard")
    (47 "F.CrtYd" user "F.Courtyard")
    (48 "B.Fab" user)
    (49 "F.Fab" user)
  )
	(footprint "antmicro-footprints:C_0402_1005Metric" (layer "F.Cu")
    (at 155.01 110.45)
    (descr "Capacitor SMD 0402")
    (tags "capacitor SMD 0402")
    (property "Author" "Antmicro")
    (property "Dielectric" "X5R")
    (property "License" "Apache-2.0")
    (property "MPN" "GRM155R61H104KE14D")
    (property "Manufacturer" "Murata")
    (property "Public" "False")
    (property "Sheetfile" "channel2.kicad_sch")
    (property "Sheetname" "Channel 2")
    (property "Val" "100n")
    (property "Voltage" "50V")
    (property "ki_description" "SMD Multilayer Ceramic Capacitor, 0.1 µF, 50 V, 0402 [1005 Metric], ± 10%, X5R, GRM Series")
    (property "ki_keywords" "0402, SMT, CAPACITOR, PASSIVE, CERAMIC, MLCC")
    (attr smd)
    (fp_text reference "C32" (at -1.52 7.52) (layer "F.SilkS")
        (effects (font (size 0.65 0.65) (thickness 0.13)) (justify left bottom))
    )
    (fp_text value "C_100n_0402" (at 0 1.4) (layer "F.Fab")
        (effects (font (size 0.65 0.65) (thickness 0.13)) (justify left bottom))
    )
    (fp_text user "${REFERENCE}" (at -0.932 3.168) (layer "F.Fab") hide
        (effects (font (size 0.7 0.7) (thickness 0.15)) (justify left bottom))
    )
    (fp_text user "Author: Antmicro" (at -0.932 4.17) (layer "F.Fab") hide
        (effects (font (size 0.7 0.7) (thickness 0.15)) (justify left bottom))
    )
    (fp_text user "License: Apache-2.0" (at -0.932 5.17) (layer "F.Fab") hide
        (effects (font (size 0.7 0.7) (thickness 0.15)) (justify left bottom))
    )
    (fp_rect (start -0.925 -0.47) (end 0.925 0.47)
      (stroke (width 0.05) (type default)) (fill none) (layer "F.CrtYd"))
    (fp_line (start -0.494 -0.25) (end 0.504 -0.25)
      (stroke (width 0.15) (type solid)) (layer "F.Fab"))
    (fp_line (start -0.494 0.248) (end -0.494 -0.25)
      (stroke (width 0.15) (type solid)) (layer "F.Fab"))
    (fp_line (start 0.504 -0.25) (end 0.504 0.248)
      (stroke (width 0.15) (type solid)) (layer "F.Fab"))
    (fp_line (start 0.504 0.248) (end -0.494 0.248)
      (stroke (width 0.15) (type solid)) (layer "F.Fab"))
    (pad "1" smd roundrect (at -0.48 0) (size 0.59 0.64) (layers "F.Cu" "F.Paste" "F.Mask") (roundrect_rratio 0.25)
      (net 2 "GND") (pintype "passive"))
    (pad "2" smd roundrect (at 0.48 0) (size 0.59 0.64) (layers "F.Cu" "F.Paste" "F.Mask") (roundrect_rratio 0.25)
      (net 23 "Net-(U4B-VDDIO1)") (pintype "passive"))
  )
	(footprint "antmicro-footprints:C_0603_1608Metric" (layer "F.Cu")
    (at 154.6 107.25)
    (descr "Capacitor SMD 0603")
    (tags "capacitor 0603")
    (property "Author" "Antmicro")
    (property "Dielectric" "")
    (property "License" "Apache-2.0")
    (property "MPN" "C1608X5R1V475M080AC")
    (property "Manufacturer" "TDK")
    (property "Public" "False")
    (property "Sheetfile" "channel2.kicad_sch")
    (property "Sheetname" "Channel 2")
    (property "Val" "4u7")
    (property "Voltage" "")
    (property "ki_description" "SMD Multilayer Ceramic Capacitor, 4.7 µF, 35 V, 0603 [1608 Metric], ± 20%, X5R, C")
    (property "ki_keywords" "0603, SMT, CAPACITOR, PASSIVE, CERAMIC, MLCC")
    (attr smd)
    (fp_text reference "C54" (at -1.1 7.65) (layer "F.SilkS")
        (effects (font (size 0.65 0.65) (thickness 0.13)) (justify left bottom))
    )
    (fp_text value "C_4u7_0603" (at 0 1.6) (layer "F.Fab")
        (effects (font (size 0.65 0.65) (thickness 0.13)) (justify left bottom))
    )
    (fp_text user "${REFERENCE}" (at -1.682 3.895) (layer "F.Fab") hide
        (effects (font (size 0.7 0.7) (thickness 0.15)) (justify left bottom))
    )
    (fp_text user "Author: Antmicro" (at -1.682 4.894) (layer "F.Fab") hide
        (effects (font (size 0.7 0.7) (thickness 0.15)) (justify left bottom))
    )
    (fp_text user "License: Apache-2.0" (at -1.682 5.895) (layer "F.Fab") hide
        (effects (font (size 0.7 0.7) (thickness 0.15)) (justify left bottom))
    )
    (fp_line (start -0.15 -0.4) (end 0.15 -0.4)
      (stroke (width 0.15) (type solid)) (layer "F.SilkS"))
    (fp_line (start -0.15 0.4) (end 0.15 0.4)
      (stroke (width 0.15) (type solid)) (layer "F.SilkS"))
    (fp_rect (start -1.25 -0.65) (end 1.25 0.65)
      (stroke (width 0.05) (type solid)) (fill none) (layer "F.CrtYd"))
    (fp_rect (start -0.8 -0.4) (end 0.8 0.4)
      (stroke (width 0.15) (type solid)) (fill none) (layer "F.Fab"))
    (pad "1" smd roundrect (at -0.7 0) (size 0.8 1) (layers "F.Cu" "F.Paste" "F.Mask") (roundrect_rratio 0.2)
      (net 2 "GND") (pintype "passive"))
    (pad "2" smd roundrect (at 0.7 0) (size 0.8 1) (layers "F.Cu" "F.Paste" "F.Mask") (roundrect_rratio 0.2)
      (net 33 "Net-(U4B-VDDC1)") (pintype "passive"))
  )
)
